(kicad_pcb
	(version 20221018)
	(generator pcbnew)
	(general
    (thickness 1.7403)
  )
	(paper "A4")
	(title_block
    (title "Data Center RDIMM DDR4 Tester")
    (date "2024-09-30")
    (rev "1.2.4")
		(comment 9 "footprints 524-533 of 690")
	)
	(layers
    (0 "F.Cu" signal)
    (1 "In1.Cu" power)
    (2 "In2.Cu" signal)
    (3 "In3.Cu" power)
    (4 "In4.Cu" power)
    (5 "In5.Cu" signal)
    (6 "In6.Cu" power)
    (7 "In7.Cu" signal)
    (8 "In8.Cu" power)
    (9 "In9.Cu" signal)
    (10 "In10.Cu" power)
    (31 "B.Cu" signal)
    (32 "B.Adhes" user "B.Adhesive")
    (33 "F.Adhes" user "F.Adhesive")
    (34 "B.Paste" user)
    (35 "F.Paste" user)
    (36 "B.SilkS" user "B.Silkscreen")
    (37 "F.SilkS" user "F.Silkscreen")
    (38 "B.Mask" user)
    (39 "F.Mask" user)
    (40 "Dwgs.User" user "User.Drawings")
    (41 "Cmts.User" user "User.Comments")
    (42 "Eco1.User" user "User.Eco1")
    (43 "Eco2.User" user "User.Eco2")
    (44 "Edge.Cuts" user)
    (45 "Margin" user)
    (46 "B.CrtYd" user "B.Courtyard")
    (47 "F.CrtYd" user "F.Courtyard")
    (48 "B.Fab" user)
    (49 "F.Fab" user)
  )
	(footprint "data-center-rdimm-ddr4-tester-footprints:C_0402_1005Metric" (layer "B.Cu")
    (at 174.386328 55.060008 90)
    (descr "Capacitor SMD 0402")
    (tags "capacitor SMD 0402")
    (property "Author" "Antmicro")
    (property "Dielectric" "X5R")
    (property "License" "Apache-2.0")
    (property "MPN" "GRM155R61H104KE14D")
    (property "Manufacturer" "Murata")
    (property "Sheetfile" "DDR4.kicad_sch")
    (property "Sheetname" "DDR4")
    (property "Val" "100n")
    (property "Voltage" "50V")
    (property "ki_description" " ")
    (attr smd)
    (fp_text reference "C165" (at 4.350008 0.363672 270) (layer "B.SilkS")
        (effects (font (size 0.7 0.7) (thickness 0.15)) (justify left bottom mirror))
    )
    (fp_text value "C_100n_0402" (at 0 -1.4 270) (layer "B.Fab") hide
        (effects (font (size 0.7 0.7) (thickness 0.15)) (justify left bottom mirror))
    )
    (fp_text user "License: Apache-2.0" (at -0.932 -5.17 270) (layer "B.Fab") hide
        (effects (font (size 0.7 0.7) (thickness 0.15)) (justify left bottom mirror))
    )
    (fp_text user "${REFERENCE}" (at -0.932 -3.168 270) (layer "B.Fab") hide
        (effects (font (size 0.7 0.7) (thickness 0.15)) (justify left bottom mirror))
    )
    (fp_text user "Author: Antmicro" (at -0.932 -4.17 270) (layer "B.Fab") hide
        (effects (font (size 0.7 0.7) (thickness 0.15)) (justify left bottom mirror))
    )
    (fp_rect (start -0.94 0.47) (end 0.94 -0.47)
      (stroke (width 0.05) (type solid)) (fill none) (layer "B.CrtYd"))
    (fp_rect (start -0.499 0.249) (end 0.499 -0.249)
      (stroke (width 0.15) (type solid)) (fill none) (layer "B.Fab"))
    (pad "1" smd roundrect (at -0.484 0 90) (size 0.59 0.64) (layers "B.Cu" "B.Paste" "B.Mask") (roundrect_rratio 0.25)
      (net 77 "VDDQ") (pintype "passive"))
    (pad "2" smd roundrect (at 0.484 0 90) (size 0.59 0.64) (layers "B.Cu" "B.Paste" "B.Mask") (roundrect_rratio 0.25)
      (net 9 "GND") (pintype "passive"))
  )
	(footprint "data-center-rdimm-ddr4-tester-footprints:C_0402_1005Metric" (layer "B.Cu")
    (at 182.886328 54.760008 90)
    (descr "Capacitor SMD 0402")
    (tags "capacitor SMD 0402")
    (property "Author" "Antmicro")
    (property "Dielectric" "X5R")
    (property "License" "Apache-2.0")
    (property "MPN" "GRM155R61H104KE14D")
    (property "Manufacturer" "Murata")
    (property "Sheetfile" "DDR4.kicad_sch")
    (property "Sheetname" "DDR4")
    (property "Val" "100n")
    (property "Voltage" "50V")
    (property "ki_description" " ")
    (attr smd)
    (fp_text reference "C164" (at 4.060008 0.483672 270) (layer "B.SilkS")
        (effects (font (size 0.7 0.7) (thickness 0.15)) (justify left bottom mirror))
    )
    (fp_text value "C_100n_0402" (at 0 -1.4 270) (layer "B.Fab") hide
        (effects (font (size 0.7 0.7) (thickness 0.15)) (justify left bottom mirror))
    )
    (fp_text user "Author: Antmicro" (at -0.932 -4.17 270) (layer "B.Fab") hide
        (effects (font (size 0.7 0.7) (thickness 0.15)) (justify left bottom mirror))
    )
    (fp_text user "License: Apache-2.0" (at -0.932 -5.17 270) (layer "B.Fab") hide
        (effects (font (size 0.7 0.7) (thickness 0.15)) (justify left bottom mirror))
    )
    (fp_text user "${REFERENCE}" (at -0.932 -3.168 270) (layer "B.Fab") hide
        (effects (font (size 0.7 0.7) (thickness 0.15)) (justify left bottom mirror))
    )
    (fp_rect (start -0.94 0.47) (end 0.94 -0.47)
      (stroke (width 0.05) (type solid)) (fill none) (layer "B.CrtYd"))
    (fp_rect (start -0.499 0.249) (end 0.499 -0.249)
      (stroke (width 0.15) (type solid)) (fill none) (layer "B.Fab"))
    (pad "1" smd roundrect (at -0.484 0 90) (size 0.59 0.64) (layers "B.Cu" "B.Paste" "B.Mask") (roundrect_rratio 0.25)
      (net 77 "VDDQ") (pintype "passive"))
    (pad "2" smd roundrect (at 0.484 0 90) (size 0.59 0.64) (layers "B.Cu" "B.Paste" "B.Mask") (roundrect_rratio 0.25)
      (net 9 "GND") (pintype "passive"))
  )
	(footprint "data-center-rdimm-ddr4-tester-footprints:C_0402_1005Metric" (layer "B.Cu")
    (at 195.646328 54.760008 90)
    (descr "Capacitor SMD 0402")
    (tags "capacitor SMD 0402")
    (property "Author" "Antmicro")
    (property "Dielectric" "X5R")
    (property "License" "Apache-2.0")
    (property "MPN" "GRM155R61H104KE14D")
    (property "Manufacturer" "Murata")
    (property "Sheetfile" "DDR4.kicad_sch")
    (property "Sheetname" "DDR4")
    (property "Val" "100n")
    (property "Voltage" "50V")
    (property "ki_description" " ")
    (attr smd)
    (fp_text reference "C154" (at 4.050008 0.423672 270) (layer "B.SilkS")
        (effects (font (size 0.7 0.7) (thickness 0.15)) (justify left bottom mirror))
    )
    (fp_text value "C_100n_0402" (at 0 -1.4 270) (layer "B.Fab") hide
        (effects (font (size 0.7 0.7) (thickness 0.15)) (justify left bottom mirror))
    )
    (fp_text user "${REFERENCE}" (at -0.932 -3.168 270) (layer "B.Fab") hide
        (effects (font (size 0.7 0.7) (thickness 0.15)) (justify left bottom mirror))
    )
    (fp_text user "License: Apache-2.0" (at -0.932 -5.17 270) (layer "B.Fab") hide
        (effects (font (size 0.7 0.7) (thickness 0.15)) (justify left bottom mirror))
    )
    (fp_text user "Author: Antmicro" (at -0.932 -4.17 270) (layer "B.Fab") hide
        (effects (font (size 0.7 0.7) (thickness 0.15)) (justify left bottom mirror))
    )
    (fp_rect (start -0.94 0.47) (end 0.94 -0.47)
      (stroke (width 0.05) (type solid)) (fill none) (layer "B.CrtYd"))
    (fp_rect (start -0.499 0.249) (end 0.499 -0.249)
      (stroke (width 0.15) (type solid)) (fill none) (layer "B.Fab"))
    (pad "1" smd roundrect (at -0.484 0 90) (size 0.59 0.64) (layers "B.Cu" "B.Paste" "B.Mask") (roundrect_rratio 0.25)
      (net 77 "VDDQ") (pintype "passive"))
    (pad "2" smd roundrect (at 0.484 0 90) (size 0.59 0.64) (layers "B.Cu" "B.Paste" "B.Mask") (roundrect_rratio 0.25)
      (net 9 "GND") (pintype "passive"))
  )
	(footprint "data-center-rdimm-ddr4-tester-footprints:C_0402_1005Metric" (layer "B.Cu")
    (at 197.336328 54.760008 90)
    (descr "Capacitor SMD 0402")
    (tags "capacitor SMD 0402")
    (property "Author" "Antmicro")
    (property "Dielectric" "X5R")
    (property "License" "Apache-2.0")
    (property "MPN" "GRM155R61H104KE14D")
    (property "Manufacturer" "Murata")
    (property "Sheetfile" "DDR4.kicad_sch")
    (property "Sheetname" "DDR4")
    (property "Val" "100n")
    (property "Voltage" "50V")
    (property "ki_description" " ")
    (attr smd)
    (fp_text reference "C153" (at 4.050008 0.423672 270) (layer "B.SilkS")
        (effects (font (size 0.7 0.7) (thickness 0.15)) (justify left bottom mirror))
    )
    (fp_text value "C_100n_0402" (at 0 -1.4 270) (layer "B.Fab") hide
        (effects (font (size 0.7 0.7) (thickness 0.15)) (justify left bottom mirror))
    )
    (fp_text user "Author: Antmicro" (at -0.932 -4.17 270) (layer "B.Fab") hide
        (effects (font (size 0.7 0.7) (thickness 0.15)) (justify left bottom mirror))
    )
    (fp_text user "License: Apache-2.0" (at -0.932 -5.17 270) (layer "B.Fab") hide
        (effects (font (size 0.7 0.7) (thickness 0.15)) (justify left bottom mirror))
    )
    (fp_text user "${REFERENCE}" (at -0.932 -3.168 270) (layer "B.Fab") hide
        (effects (font (size 0.7 0.7) (thickness 0.15)) (justify left bottom mirror))
    )
    (fp_rect (start -0.94 0.47) (end 0.94 -0.47)
      (stroke (width 0.05) (type solid)) (fill none) (layer "B.CrtYd"))
    (fp_rect (start -0.499 0.249) (end 0.499 -0.249)
      (stroke (width 0.15) (type solid)) (fill none) (layer "B.Fab"))
    (pad "1" smd roundrect (at -0.484 0 90) (size 0.59 0.64) (layers "B.Cu" "B.Paste" "B.Mask") (roundrect_rratio 0.25)
      (net 77 "VDDQ") (pintype "passive"))
    (pad "2" smd roundrect (at 0.484 0 90) (size 0.59 0.64) (layers "B.Cu" "B.Paste" "B.Mask") (roundrect_rratio 0.25)
      (net 9 "GND") (pintype "passive"))
  )
	(footprint "data-center-rdimm-ddr4-tester-footprints:C_0402_1005Metric" (layer "B.Cu")
    (at 182.886328 59.297408 -90)
    (descr "Capacitor SMD 0402")
    (tags "capacitor SMD 0402")
    (property "Author" "Antmicro")
    (property "Dielectric" "X5R")
    (property "License" "Apache-2.0")
    (property "MPN" "GRM155R61H104KE14D")
    (property "Manufacturer" "Murata")
    (property "Sheetfile" "DDR4.kicad_sch")
    (property "Sheetname" "DDR4")
    (property "Val" "100n")
    (property "Voltage" "50V")
    (property "ki_description" " ")
    (attr smd)
    (fp_text reference "C208" (at 0.762592 -0.353672 90) (layer "B.SilkS")
        (effects (font (size 0.7 0.7) (thickness 0.15)) (justify left bottom mirror))
    )
    (fp_text value "C_100n_0402" (at 0 -1.4 90) (layer "B.Fab") hide
        (effects (font (size 0.7 0.7) (thickness 0.15)) (justify left bottom mirror))
    )
    (fp_text user "License: Apache-2.0" (at -0.932 -5.17 90) (layer "B.Fab") hide
        (effects (font (size 0.7 0.7) (thickness 0.15)) (justify left bottom mirror))
    )
    (fp_text user "${REFERENCE}" (at -0.932 -3.168 90) (layer "B.Fab") hide
        (effects (font (size 0.7 0.7) (thickness 0.15)) (justify left bottom mirror))
    )
    (fp_text user "Author: Antmicro" (at -0.932 -4.17 90) (layer "B.Fab") hide
        (effects (font (size 0.7 0.7) (thickness 0.15)) (justify left bottom mirror))
    )
    (fp_rect (start -0.94 0.47) (end 0.94 -0.47)
      (stroke (width 0.05) (type solid)) (fill none) (layer "B.CrtYd"))
    (fp_rect (start -0.499 0.249) (end 0.499 -0.249)
      (stroke (width 0.15) (type solid)) (fill none) (layer "B.Fab"))
    (pad "1" smd roundrect (at -0.484 0 270) (size 0.59 0.64) (layers "B.Cu" "B.Paste" "B.Mask") (roundrect_rratio 0.25)
      (net 77 "VDDQ") (pintype "passive"))
    (pad "2" smd roundrect (at 0.484 0 270) (size 0.59 0.64) (layers "B.Cu" "B.Paste" "B.Mask") (roundrect_rratio 0.25)
      (net 9 "GND") (pintype "passive"))
  )
	(footprint "data-center-rdimm-ddr4-tester-footprints:C_0402_1005Metric" (layer "B.Cu")
    (at 194.732928 57.951208 90)
    (descr "Capacitor SMD 0402")
    (tags "capacitor SMD 0402")
    (property "Author" "Antmicro")
    (property "Dielectric" "X5R")
    (property "License" "Apache-2.0")
    (property "MPN" "GRM155R61H104KE14D")
    (property "Manufacturer" "Murata")
    (property "Sheetfile" "DDR4.kicad_sch")
    (property "Sheetname" "DDR4")
    (property "Val" "100n")
    (property "Voltage" "50V")
    (property "ki_description" " ")
    (attr smd)
    (fp_text reference "C209" (at -0.878792 0.370872 270) (layer "B.SilkS")
        (effects (font (size 0.7 0.7) (thickness 0.15)) (justify left bottom mirror))
    )
    (fp_text value "C_100n_0402" (at 0 -1.4 270) (layer "B.Fab") hide
        (effects (font (size 0.7 0.7) (thickness 0.15)) (justify left bottom mirror))
    )
    (fp_text user "License: Apache-2.0" (at -0.932 -5.17 270) (layer "B.Fab") hide
        (effects (font (size 0.7 0.7) (thickness 0.15)) (justify left bottom mirror))
    )
    (fp_text user "${REFERENCE}" (at -0.932 -3.168 270) (layer "B.Fab") hide
        (effects (font (size 0.7 0.7) (thickness 0.15)) (justify left bottom mirror))
    )
    (fp_text user "Author: Antmicro" (at -0.932 -4.17 270) (layer "B.Fab") hide
        (effects (font (size 0.7 0.7) (thickness 0.15)) (justify left bottom mirror))
    )
    (fp_rect (start -0.94 0.47) (end 0.94 -0.47)
      (stroke (width 0.05) (type solid)) (fill none) (layer "B.CrtYd"))
    (fp_rect (start -0.499 0.249) (end 0.499 -0.249)
      (stroke (width 0.15) (type solid)) (fill none) (layer "B.Fab"))
    (pad "1" smd roundrect (at -0.484 0 90) (size 0.59 0.64) (layers "B.Cu" "B.Paste" "B.Mask") (roundrect_rratio 0.25)
      (net 77 "VDDQ") (pintype "passive"))
    (pad "2" smd roundrect (at 0.484 0 90) (size 0.59 0.64) (layers "B.Cu" "B.Paste" "B.Mask") (roundrect_rratio 0.25)
      (net 9 "GND") (pintype "passive"))
  )
	(footprint "data-center-rdimm-ddr4-tester-footprints:C_0402_1005Metric" (layer "B.Cu")
    (at 198.2 59)
    (descr "Capacitor SMD 0402")
    (tags "capacitor SMD 0402")
    (property "Author" "Antmicro")
    (property "Dielectric" "X5R")
    (property "License" "Apache-2.0")
    (property "MPN" "GRM155R61H104KE14D")
    (property "Manufacturer" "Murata")
    (property "Sheetfile" "DDR4.kicad_sch")
    (property "Sheetname" "DDR4")
    (property "Val" "100n")
    (property "Voltage" "50V")
    (property "ki_description" " ")
    (attr smd)
    (fp_text reference "C211" (at 1.4 1.31 180) (layer "B.SilkS")
        (effects (font (size 0.7 0.7) (thickness 0.15)) (justify left bottom mirror))
    )
    (fp_text value "C_100n_0402" (at 0 -1.4 180) (layer "B.Fab") hide
        (effects (font (size 0.7 0.7) (thickness 0.15)) (justify left bottom mirror))
    )
    (fp_text user "Author: Antmicro" (at -0.932 -4.17 180) (layer "B.Fab") hide
        (effects (font (size 0.7 0.7) (thickness 0.15)) (justify left bottom mirror))
    )
    (fp_text user "${REFERENCE}" (at -0.932 -3.168 180) (layer "B.Fab") hide
        (effects (font (size 0.7 0.7) (thickness 0.15)) (justify left bottom mirror))
    )
    (fp_text user "License: Apache-2.0" (at -0.932 -5.17 180) (layer "B.Fab") hide
        (effects (font (size 0.7 0.7) (thickness 0.15)) (justify left bottom mirror))
    )
    (fp_rect (start -0.94 0.47) (end 0.94 -0.47)
      (stroke (width 0.05) (type solid)) (fill none) (layer "B.CrtYd"))
    (fp_rect (start -0.499 0.249) (end 0.499 -0.249)
      (stroke (width 0.15) (type solid)) (fill none) (layer "B.Fab"))
    (pad "1" smd roundrect (at -0.484 0) (size 0.59 0.64) (layers "B.Cu" "B.Paste" "B.Mask") (roundrect_rratio 0.25)
      (net 77 "VDDQ") (pintype "passive"))
    (pad "2" smd roundrect (at 0.484 0) (size 0.59 0.64) (layers "B.Cu" "B.Paste" "B.Mask") (roundrect_rratio 0.25)
      (net 9 "GND") (pintype "passive"))
  )
	(footprint "data-center-rdimm-ddr4-tester-footprints:C_0402_1005Metric" (layer "B.Cu")
    (at 192.091328 57.951208 90)
    (descr "Capacitor SMD 0402")
    (tags "capacitor SMD 0402")
    (property "Author" "Antmicro")
    (property "Dielectric" "X5R")
    (property "License" "Apache-2.0")
    (property "MPN" "GRM155R61H104KE14D")
    (property "Manufacturer" "Murata")
    (property "Sheetfile" "DDR4.kicad_sch")
    (property "Sheetname" "DDR4")
    (property "Val" "100n")
    (property "Voltage" "50V")
    (property "ki_description" " ")
    (attr smd)
    (fp_text reference "C212" (at -0.878792 0.370872 270) (layer "B.SilkS")
        (effects (font (size 0.7 0.7) (thickness 0.15)) (justify left bottom mirror))
    )
    (fp_text value "C_100n_0402" (at 0 -1.4 270) (layer "B.Fab") hide
        (effects (font (size 0.7 0.7) (thickness 0.15)) (justify left bottom mirror))
    )
    (fp_text user "Author: Antmicro" (at -0.932 -4.17 270) (layer "B.Fab") hide
        (effects (font (size 0.7 0.7) (thickness 0.15)) (justify left bottom mirror))
    )
    (fp_text user "${REFERENCE}" (at -0.932 -3.168 270) (layer "B.Fab") hide
        (effects (font (size 0.7 0.7) (thickness 0.15)) (justify left bottom mirror))
    )
    (fp_text user "License: Apache-2.0" (at -0.932 -5.17 270) (layer "B.Fab") hide
        (effects (font (size 0.7 0.7) (thickness 0.15)) (justify left bottom mirror))
    )
    (fp_rect (start -0.94 0.47) (end 0.94 -0.47)
      (stroke (width 0.05) (type solid)) (fill none) (layer "B.CrtYd"))
    (fp_rect (start -0.499 0.249) (end 0.499 -0.249)
      (stroke (width 0.15) (type solid)) (fill none) (layer "B.Fab"))
    (pad "1" smd roundrect (at -0.484 0 90) (size 0.59 0.64) (layers "B.Cu" "B.Paste" "B.Mask") (roundrect_rratio 0.25)
      (net 77 "VDDQ") (pintype "passive"))
    (pad "2" smd roundrect (at 0.484 0 90) (size 0.59 0.64) (layers "B.Cu" "B.Paste" "B.Mask") (roundrect_rratio 0.25)
      (net 9 "GND") (pintype "passive"))
  )
	(footprint "data-center-rdimm-ddr4-tester-footprints:C_0402_1005Metric" (layer "B.Cu")
    (at 187.189128 57.951208 90)
    (descr "Capacitor SMD 0402")
    (tags "capacitor SMD 0402")
    (property "Author" "Antmicro")
    (property "Dielectric" "X5R")
    (property "License" "Apache-2.0")
    (property "MPN" "GRM155R61H104KE14D")
    (property "Manufacturer" "Murata")
    (property "Sheetfile" "DDR4.kicad_sch")
    (property "Sheetname" "DDR4")
    (property "Val" "100n")
    (property "Voltage" "50V")
    (property "ki_description" " ")
    (attr smd)
    (fp_text reference "C213" (at -0.878792 0.370872 270) (layer "B.SilkS")
        (effects (font (size 0.7 0.7) (thickness 0.15)) (justify left bottom mirror))
    )
    (fp_text value "C_100n_0402" (at 0 -1.4 270) (layer "B.Fab") hide
        (effects (font (size 0.7 0.7) (thickness 0.15)) (justify left bottom mirror))
    )
    (fp_text user "Author: Antmicro" (at -0.932 -4.17 270) (layer "B.Fab") hide
        (effects (font (size 0.7 0.7) (thickness 0.15)) (justify left bottom mirror))
    )
    (fp_text user "${REFERENCE}" (at -0.932 -3.168 270) (layer "B.Fab") hide
        (effects (font (size 0.7 0.7) (thickness 0.15)) (justify left bottom mirror))
    )
    (fp_text user "License: Apache-2.0" (at -0.932 -5.17 270) (layer "B.Fab") hide
        (effects (font (size 0.7 0.7) (thickness 0.15)) (justify left bottom mirror))
    )
    (fp_rect (start -0.94 0.47) (end 0.94 -0.47)
      (stroke (width 0.05) (type solid)) (fill none) (layer "B.CrtYd"))
    (fp_rect (start -0.499 0.249) (end 0.499 -0.249)
      (stroke (width 0.15) (type solid)) (fill none) (layer "B.Fab"))
    (pad "1" smd roundrect (at -0.484 0 90) (size 0.59 0.64) (layers "B.Cu" "B.Paste" "B.Mask") (roundrect_rratio 0.25)
      (net 77 "VDDQ") (pintype "passive"))
    (pad "2" smd roundrect (at 0.484 0 90) (size 0.59 0.64) (layers "B.Cu" "B.Paste" "B.Mask") (roundrect_rratio 0.25)
      (net 9 "GND") (pintype "passive"))
  )
	(footprint "data-center-rdimm-ddr4-tester-footprints:C_0402_1005Metric" (layer "B.Cu")
    (at 189.779928 57.951208 90)
    (descr "Capacitor SMD 0402")
    (tags "capacitor SMD 0402")
    (property "Author" "Antmicro")
    (property "Dielectric" "X5R")
    (property "License" "Apache-2.0")
    (property "MPN" "GRM155R61H104KE14D")
    (property "Manufacturer" "Murata")
    (property "Sheetfile" "DDR4.kicad_sch")
    (property "Sheetname" "DDR4")
    (property "Val" "100n")
    (property "Voltage" "50V")
    (property "ki_description" " ")
    (attr smd)
    (fp_text reference "C214" (at -0.878792 0.370872 270) (layer "B.SilkS")
        (effects (font (size 0.7 0.7) (thickness 0.15)) (justify left bottom mirror))
    )
    (fp_text value "C_100n_0402" (at 0 -1.4 270) (layer "B.Fab") hide
        (effects (font (size 0.7 0.7) (thickness 0.15)) (justify left bottom mirror))
    )
    (fp_text user "License: Apache-2.0" (at -0.932 -5.17 270) (layer "B.Fab") hide
        (effects (font (size 0.7 0.7) (thickness 0.15)) (justify left bottom mirror))
    )
    (fp_text user "Author: Antmicro" (at -0.932 -4.17 270) (layer "B.Fab") hide
        (effects (font (size 0.7 0.7) (thickness 0.15)) (justify left bottom mirror))
    )
    (fp_text user "${REFERENCE}" (at -0.932 -3.168 270) (layer "B.Fab") hide
        (effects (font (size 0.7 0.7) (thickness 0.15)) (justify left bottom mirror))
    )
    (fp_rect (start -0.94 0.47) (end 0.94 -0.47)
      (stroke (width 0.05) (type solid)) (fill none) (layer "B.CrtYd"))
    (fp_rect (start -0.499 0.249) (end 0.499 -0.249)
      (stroke (width 0.15) (type solid)) (fill none) (layer "B.Fab"))
    (pad "1" smd roundrect (at -0.484 0 90) (size 0.59 0.64) (layers "B.Cu" "B.Paste" "B.Mask") (roundrect_rratio 0.25)
      (net 77 "VDDQ") (pintype "passive"))
    (pad "2" smd roundrect (at 0.484 0 90) (size 0.59 0.64) (layers "B.Cu" "B.Paste" "B.Mask") (roundrect_rratio 0.25)
      (net 9 "GND") (pintype "passive"))
  )
)
